(kicad_pcb
	(version 20260206)
	(generator "pcbnew")
	(generator_version "10.0")
	(general
		(thickness 1.6)
		(legacy_teardrops no)
	)
	(paper "A4")
	(title_block
		(title "01162023_DA0F0TEBIF0_F0T_Expander_BD_F_brd_V02_OCP.brd")
		(comment 1 "Grand Teton / footprints 1591-1596 of 9728")
	)
	(layers
		(0 "F.Cu" signal "TOP")
		(4 "In1.Cu" signal "GND")
		(6 "In2.Cu" signal "VCC")
		(8 "In3.Cu" signal "VCC1")
		(10 "In4.Cu" signal "GND1")
		(12 "In5.Cu" signal "IN1")
		(14 "In6.Cu" signal "GND2")
		(16 "In7.Cu" signal "IN2")
		(18 "In8.Cu" signal "GND3")
		(20 "In9.Cu" signal "IN3")
		(22 "In10.Cu" signal "GND4")
		(24 "In11.Cu" signal "IN4")
		(26 "In12.Cu" signal "GND5")
		(28 "In13.Cu" signal "IN5")
		(30 "In14.Cu" signal "GND6")
		(32 "In15.Cu" signal "IN6")
		(34 "In16.Cu" signal "GND7")
		(2 "B.Cu" signal "BOTTOM")
		(9 "F.Adhes" user "F.Adhesive")
		(11 "B.Adhes" user "B.Adhesive")
		(13 "F.Paste" user "Package Geometry/Pastemask Top")
		(15 "B.Paste" user "Package Geometry/Pastemask Bottom")
		(5 "F.SilkS" user "Ref Des/Silkscreen Top")
		(7 "B.SilkS" user "Ref Des/Silkscreen Bottom")
		(1 "F.Mask" user "Board Geometry/Soldermask Top")
		(3 "B.Mask" user "Board Geometry/Soldermask Bottom")
		(17 "Dwgs.User" user "User.Drawings")
		(19 "Cmts.User" user "User.Comments")
		(21 "Eco1.User" user "User.Eco1")
		(23 "Eco2.User" user "User.Eco2")
		(25 "Edge.Cuts" user "Board Geometry/Outline")
		(27 "Margin" user)
		(31 "F.CrtYd" user "Package Geometry/Place Bound Top")
		(29 "B.CrtYd" user "Package Geometry/Place Bound Bottom")
		(35 "F.Fab" user "Ref Des/Assembly Top")
		(33 "B.Fab" user "Ref Des/Assembly Bottom")
	)
	(footprint ""
		(layer "F.Cu")
		(at 46.487588 -25.342342 -90)
		(property "Reference" "R414"
			(at 0 0 270)
			(layer "F.SilkS")
			(hide yes)
			(effects
				(font
					(size 1.27 1.27)
				)
			)
		)
		(property "Value" ""
			(at 0 0 270)
			(layer "F.Fab")
			(effects
				(font
					(size 1.27 1.27)
				)
			)
		)
		(duplicate_pad_numbers_are_jumpers no)
		(fp_line
			(start -0.7874 0.4064)
			(end -0.7874 -0.4064)
			(stroke
				(width 0.1524)
				(type default)
			)
			(layer "F.SilkS")
		)
		(fp_line
			(start 0.7874 0.4064)
			(end -0.7874 0.4064)
			(stroke
				(width 0.1524)
				(type default)
			)
			(layer "F.SilkS")
		)
		(fp_line
			(start -0.7874 -0.4064)
			(end 0.7874 -0.4064)
			(stroke
				(width 0.1524)
				(type default)
			)
			(layer "F.SilkS")
		)
		(fp_line
			(start 0.7874 -0.4064)
			(end 0.7874 0.4064)
			(stroke
				(width 0.1524)
				(type default)
			)
			(layer "F.SilkS")
		)
		(fp_line
			(start -0.67945 0.3048)
			(end -0.67945 -0.305054)
			(stroke
				(width 0.1)
				(type default)
			)
			(layer "F.Fab")
		)
		(fp_line
			(start -0.12065 0.3048)
			(end -0.67945 0.3048)
			(stroke
				(width 0.1)
				(type default)
			)
			(layer "F.Fab")
		)
		(fp_line
			(start 0.120396 0.3048)
			(end 0.120396 0.2794)
			(stroke
				(width 0.1)
				(type default)
			)
			(layer "F.Fab")
		)
		(fp_line
			(start 0.67945 0.3048)
			(end 0.120396 0.3048)
			(stroke
				(width 0.1)
				(type default)
			)
			(layer "F.Fab")
		)
		(fp_line
			(start -0.12065 0.2794)
			(end -0.12065 0.3048)
			(stroke
				(width 0.1)
				(type default)
			)
			(layer "F.Fab")
		)
		(fp_line
			(start 0.120396 0.2794)
			(end -0.12065 0.2794)
			(stroke
				(width 0.1)
				(type default)
			)
			(layer "F.Fab")
		)
		(fp_line
			(start -0.12065 -0.2794)
			(end 0.12065 -0.2794)
			(stroke
				(width 0.1)
				(type default)
			)
			(layer "F.Fab")
		)
		(fp_line
			(start 0.12065 -0.2794)
			(end 0.12065 -0.3048)
			(stroke
				(width 0.1)
				(type default)
			)
			(layer "F.Fab")
		)
		(fp_line
			(start 0.12065 -0.3048)
			(end 0.67945 -0.3048)
			(stroke
				(width 0.1)
				(type default)
			)
			(layer "F.Fab")
		)
		(fp_line
			(start 0.67945 -0.3048)
			(end 0.67945 0.3048)
			(stroke
				(width 0.1)
				(type default)
			)
			(layer "F.Fab")
		)
		(fp_line
			(start -0.67945 -0.305054)
			(end -0.12065 -0.305054)
			(stroke
				(width 0.1)
				(type default)
			)
			(layer "F.Fab")
		)
		(fp_line
			(start -0.12065 -0.305054)
			(end -0.12065 -0.2794)
			(stroke
				(width 0.1)
				(type default)
			)
			(layer "F.Fab")
		)
		(pad "1" smd circle
			(at -0.40005 0 270)
			(size 0 0)
			(layers "F.Cu" "F.Mask" "F.Paste")
			(net "GND")
		)
		(pad "2" smd circle
			(at 0.40005 0 270)
			(size 0 0)
			(layers "F.Cu" "F.Mask" "F.Paste")
			(net "DUALPORT_N_SSD1")
		)
	)
	(footprint ""
		(layer "F.Cu")
		(at 387.06044 -117.7544 180)
		(property "Reference" "R313"
			(at 0 0 180)
			(layer "F.SilkS")
			(hide yes)
			(effects
				(font
					(size 1.27 1.27)
				)
			)
		)
		(property "Value" ""
			(at 0 0 180)
			(layer "F.Fab")
			(effects
				(font
					(size 1.27 1.27)
				)
			)
		)
		(duplicate_pad_numbers_are_jumpers no)
		(fp_line
			(start 0.7874 0.4064)
			(end -0.7874 0.4064)
			(stroke
				(width 0.1524)
				(type default)
			)
			(layer "F.SilkS")
		)
		(fp_line
			(start 0.7874 -0.4064)
			(end 0.7874 0.4064)
			(stroke
				(width 0.1524)
				(type default)
			)
			(layer "F.SilkS")
		)
		(fp_line
			(start -0.7874 0.4064)
			(end -0.7874 -0.4064)
			(stroke
				(width 0.1524)
				(type default)
			)
			(layer "F.SilkS")
		)
		(fp_line
			(start -0.7874 -0.4064)
			(end 0.7874 -0.4064)
			(stroke
				(width 0.1524)
				(type default)
			)
			(layer "F.SilkS")
		)
		(fp_line
			(start 0.67945 0.3048)
			(end 0.120396 0.3048)
			(stroke
				(width 0.1)
				(type default)
			)
			(layer "F.Fab")
		)
		(fp_line
			(start 0.67945 -0.3048)
			(end 0.67945 0.3048)
			(stroke
				(width 0.1)
				(type default)
			)
			(layer "F.Fab")
		)
		(fp_line
			(start 0.12065 -0.2794)
			(end 0.12065 -0.3048)
			(stroke
				(width 0.1)
				(type default)
			)
			(layer "F.Fab")
		)
		(fp_line
			(start 0.12065 -0.3048)
			(end 0.67945 -0.3048)
			(stroke
				(width 0.1)
				(type default)
			)
			(layer "F.Fab")
		)
		(fp_line
			(start 0.120396 0.3048)
			(end 0.120396 0.2794)
			(stroke
				(width 0.1)
				(type default)
			)
			(layer "F.Fab")
		)
		(fp_line
			(start 0.120396 0.2794)
			(end -0.12065 0.2794)
			(stroke
				(width 0.1)
				(type default)
			)
			(layer "F.Fab")
		)
		(fp_line
			(start -0.12065 0.3048)
			(end -0.67945 0.3048)
			(stroke
				(width 0.1)
				(type default)
			)
			(layer "F.Fab")
		)
		(fp_line
			(start -0.12065 0.2794)
			(end -0.12065 0.3048)
			(stroke
				(width 0.1)
				(type default)
			)
			(layer "F.Fab")
		)
		(fp_line
			(start -0.12065 -0.2794)
			(end 0.12065 -0.2794)
			(stroke
				(width 0.1)
				(type default)
			)
			(layer "F.Fab")
		)
		(fp_line
			(start -0.12065 -0.305054)
			(end -0.12065 -0.2794)
			(stroke
				(width 0.1)
				(type default)
			)
			(layer "F.Fab")
		)
		(fp_line
			(start -0.67945 0.3048)
			(end -0.67945 -0.305054)
			(stroke
				(width 0.1)
				(type default)
			)
			(layer "F.Fab")
		)
		(fp_line
			(start -0.67945 -0.305054)
			(end -0.12065 -0.305054)
			(stroke
				(width 0.1)
				(type default)
			)
			(layer "F.Fab")
		)
		(pad "1" smd circle
			(at -0.40005 0 180)
			(size 0 0)
			(layers "F.Cu" "F.Mask" "F.Paste")
			(net "PRSNTB0_NIC6_N")
		)
		(pad "2" smd circle
			(at 0.40005 0 180)
			(size 0 0)
			(layers "F.Cu" "F.Mask" "F.Paste")
			(net "P3V3_AUX")
		)
	)
	(footprint ""
		(layer "F.Cu")
		(at 238.909098 -26.03373)
		(property "Reference" "R4068"
			(at 0 0 0)
			(layer "F.SilkS")
			(hide yes)
			(effects
				(font
					(size 1.27 1.27)
				)
			)
		)
		(property "Value" ""
			(at 0 0 0)
			(layer "F.Fab")
			(effects
				(font
					(size 1.27 1.27)
				)
			)
		)
		(duplicate_pad_numbers_are_jumpers no)
		(fp_line
			(start -0.7874 -0.4064)
			(end 0.7874 -0.4064)
			(stroke
				(width 0.1524)
				(type default)
			)
			(layer "F.SilkS")
		)
		(fp_line
			(start -0.7874 0.4064)
			(end -0.7874 -0.4064)
			(stroke
				(width 0.1524)
				(type default)
			)
			(layer "F.SilkS")
		)
		(fp_line
			(start 0.7874 -0.4064)
			(end 0.7874 0.4064)
			(stroke
				(width 0.1524)
				(type default)
			)
			(layer "F.SilkS")
		)
		(fp_line
			(start 0.7874 0.4064)
			(end -0.7874 0.4064)
			(stroke
				(width 0.1524)
				(type default)
			)
			(layer "F.SilkS")
		)
		(fp_line
			(start -0.67945 -0.305054)
			(end -0.12065 -0.305054)
			(stroke
				(width 0.1)
				(type default)
			)
			(layer "F.Fab")
		)
		(fp_line
			(start -0.67945 0.3048)
			(end -0.67945 -0.305054)
			(stroke
				(width 0.1)
				(type default)
			)
			(layer "F.Fab")
		)
		(fp_line
			(start -0.12065 -0.305054)
			(end -0.12065 -0.2794)
			(stroke
				(width 0.1)
				(type default)
			)
			(layer "F.Fab")
		)
		(fp_line
			(start -0.12065 -0.2794)
			(end 0.12065 -0.2794)
			(stroke
				(width 0.1)
				(type default)
			)
			(layer "F.Fab")
		)
		(fp_line
			(start -0.12065 0.2794)
			(end -0.12065 0.3048)
			(stroke
				(width 0.1)
				(type default)
			)
			(layer "F.Fab")
		)
		(fp_line
			(start -0.12065 0.3048)
			(end -0.67945 0.3048)
			(stroke
				(width 0.1)
				(type default)
			)
			(layer "F.Fab")
		)
		(fp_line
			(start 0.120396 0.2794)
			(end -0.12065 0.2794)
			(stroke
				(width 0.1)
				(type default)
			)
			(layer "F.Fab")
		)
		(fp_line
			(start 0.120396 0.3048)
			(end 0.120396 0.2794)
			(stroke
				(width 0.1)
				(type default)
			)
			(layer "F.Fab")
		)
		(fp_line
			(start 0.12065 -0.3048)
			(end 0.67945 -0.3048)
			(stroke
				(width 0.1)
				(type default)
			)
			(layer "F.Fab")
		)
		(fp_line
			(start 0.12065 -0.2794)
			(end 0.12065 -0.3048)
			(stroke
				(width 0.1)
				(type default)
			)
			(layer "F.Fab")
		)
		(fp_line
			(start 0.67945 -0.3048)
			(end 0.67945 0.3048)
			(stroke
				(width 0.1)
				(type default)
			)
			(layer "F.Fab")
		)
		(fp_line
			(start 0.67945 0.3048)
			(end 0.120396 0.3048)
			(stroke
				(width 0.1)
				(type default)
			)
			(layer "F.Fab")
		)
		(pad "1" smd circle
			(at -0.40005 0)
			(size 0 0)
			(layers "F.Cu" "F.Mask" "F.Paste")
			(net "P3V3_AUX")
		)
		(pad "2" smd circle
			(at 0.40005 0)
			(size 0 0)
			(layers "F.Cu" "F.Mask" "F.Paste")
			(net "PRSNT_SSD8_R_N")
		)
	)
	(footprint ""
		(layer "F.Cu")
		(at 276.073616 -405.074374 90)
		(property "Reference" "R1821"
			(at 0 0 90)
			(layer "F.SilkS")
			(hide yes)
			(effects
				(font
					(size 1.27 1.27)
				)
			)
		)
		(property "Value" ""
			(at 0 0 90)
			(layer "F.Fab")
			(effects
				(font
					(size 1.27 1.27)
				)
			)
		)
		(duplicate_pad_numbers_are_jumpers no)
		(fp_line
			(start 0.7874 -0.4064)
			(end 0.7874 0.4064)
			(stroke
				(width 0.1524)
				(type default)
			)
			(layer "F.SilkS")
		)
		(fp_line
			(start -0.7874 -0.4064)
			(end 0.7874 -0.4064)
			(stroke
				(width 0.1524)
				(type default)
			)
			(layer "F.SilkS")
		)
		(fp_line
			(start 0.7874 0.4064)
			(end -0.7874 0.4064)
			(stroke
				(width 0.1524)
				(type default)
			)
			(layer "F.SilkS")
		)
		(fp_line
			(start -0.7874 0.4064)
			(end -0.7874 -0.4064)
			(stroke
				(width 0.1524)
				(type default)
			)
			(layer "F.SilkS")
		)
		(fp_line
			(start -0.12065 -0.305054)
			(end -0.12065 -0.2794)
			(stroke
				(width 0.1)
				(type default)
			)
			(layer "F.Fab")
		)
		(fp_line
			(start -0.67945 -0.305054)
			(end -0.12065 -0.305054)
			(stroke
				(width 0.1)
				(type default)
			)
			(layer "F.Fab")
		)
		(fp_line
			(start 0.67945 -0.3048)
			(end 0.67945 0.3048)
			(stroke
				(width 0.1)
				(type default)
			)
			(layer "F.Fab")
		)
		(fp_line
			(start 0.12065 -0.3048)
			(end 0.67945 -0.3048)
			(stroke
				(width 0.1)
				(type default)
			)
			(layer "F.Fab")
		)
		(fp_line
			(start 0.12065 -0.2794)
			(end 0.12065 -0.3048)
			(stroke
				(width 0.1)
				(type default)
			)
			(layer "F.Fab")
		)
		(fp_line
			(start -0.12065 -0.2794)
			(end 0.12065 -0.2794)
			(stroke
				(width 0.1)
				(type default)
			)
			(layer "F.Fab")
		)
		(fp_line
			(start 0.120396 0.2794)
			(end -0.12065 0.2794)
			(stroke
				(width 0.1)
				(type default)
			)
			(layer "F.Fab")
		)
		(fp_line
			(start -0.12065 0.2794)
			(end -0.12065 0.3048)
			(stroke
				(width 0.1)
				(type default)
			)
			(layer "F.Fab")
		)
		(fp_line
			(start 0.67945 0.3048)
			(end 0.120396 0.3048)
			(stroke
				(width 0.1)
				(type default)
			)
			(layer "F.Fab")
		)
		(fp_line
			(start 0.120396 0.3048)
			(end 0.120396 0.2794)
			(stroke
				(width 0.1)
				(type default)
			)
			(layer "F.Fab")
		)
		(fp_line
			(start -0.12065 0.3048)
			(end -0.67945 0.3048)
			(stroke
				(width 0.1)
				(type default)
			)
			(layer "F.Fab")
		)
		(fp_line
			(start -0.67945 0.3048)
			(end -0.67945 -0.305054)
			(stroke
				(width 0.1)
				(type default)
			)
			(layer "F.Fab")
		)
		(pad "1" smd circle
			(at -0.40005 0 90)
			(size 0 0)
			(layers "F.Cu" "F.Mask" "F.Paste")
			(net "BIC_SYS_READY_R_N")
		)
		(pad "2" smd circle
			(at 0.40005 0 90)
			(size 0 0)
			(layers "F.Cu" "F.Mask" "F.Paste")
			(net "BIC_SYS_READY_R2_N")
		)
	)
	(footprint ""
		(layer "F.Cu")
		(at 101.930454 -119.77624)
		(property "Reference" "R5857"
			(at 0 0 0)
			(layer "F.SilkS")
			(hide yes)
			(effects
				(font
					(size 1.27 1.27)
				)
			)
		)
		(property "Value" ""
			(at 0 0 0)
			(layer "F.Fab")
			(effects
				(font
					(size 1.27 1.27)
				)
			)
		)
		(duplicate_pad_numbers_are_jumpers no)
		(fp_line
			(start -0.7874 -0.4064)
			(end 0.7874 -0.4064)
			(stroke
				(width 0.1524)
				(type default)
			)
			(layer "F.SilkS")
		)
		(fp_line
			(start -0.7874 0.4064)
			(end -0.7874 -0.4064)
			(stroke
				(width 0.1524)
				(type default)
			)
			(layer "F.SilkS")
		)
		(fp_line
			(start 0.7874 -0.4064)
			(end 0.7874 0.4064)
			(stroke
				(width 0.1524)
				(type default)
			)
			(layer "F.SilkS")
		)
		(fp_line
			(start 0.7874 0.4064)
			(end -0.7874 0.4064)
			(stroke
				(width 0.1524)
				(type default)
			)
			(layer "F.SilkS")
		)
		(fp_line
			(start -0.67945 -0.305054)
			(end -0.12065 -0.305054)
			(stroke
				(width 0.1)
				(type default)
			)
			(layer "F.Fab")
		)
		(fp_line
			(start -0.67945 0.3048)
			(end -0.67945 -0.305054)
			(stroke
				(width 0.1)
				(type default)
			)
			(layer "F.Fab")
		)
		(fp_line
			(start -0.12065 -0.305054)
			(end -0.12065 -0.2794)
			(stroke
				(width 0.1)
				(type default)
			)
			(layer "F.Fab")
		)
		(fp_line
			(start -0.12065 -0.2794)
			(end 0.12065 -0.2794)
			(stroke
				(width 0.1)
				(type default)
			)
			(layer "F.Fab")
		)
		(fp_line
			(start -0.12065 0.2794)
			(end -0.12065 0.3048)
			(stroke
				(width 0.1)
				(type default)
			)
			(layer "F.Fab")
		)
		(fp_line
			(start -0.12065 0.3048)
			(end -0.67945 0.3048)
			(stroke
				(width 0.1)
				(type default)
			)
			(layer "F.Fab")
		)
		(fp_line
			(start 0.120396 0.2794)
			(end -0.12065 0.2794)
			(stroke
				(width 0.1)
				(type default)
			)
			(layer "F.Fab")
		)
		(fp_line
			(start 0.120396 0.3048)
			(end 0.120396 0.2794)
			(stroke
				(width 0.1)
				(type default)
			)
			(layer "F.Fab")
		)
		(fp_line
			(start 0.12065 -0.3048)
			(end 0.67945 -0.3048)
			(stroke
				(width 0.1)
				(type default)
			)
			(layer "F.Fab")
		)
		(fp_line
			(start 0.12065 -0.2794)
			(end 0.12065 -0.3048)
			(stroke
				(width 0.1)
				(type default)
			)
			(layer "F.Fab")
		)
		(fp_line
			(start 0.67945 -0.3048)
			(end 0.67945 0.3048)
			(stroke
				(width 0.1)
				(type default)
			)
			(layer "F.Fab")
		)
		(fp_line
			(start 0.67945 0.3048)
			(end 0.120396 0.3048)
			(stroke
				(width 0.1)
				(type default)
			)
			(layer "F.Fab")
		)
		(pad "1" smd circle
			(at -0.40005 0)
			(size 0 0)
			(layers "F.Cu" "F.Mask" "F.Paste")
			(net "P3V3_AUX")
		)
		(pad "2" smd circle
			(at 0.40005 0)
			(size 0 0)
			(layers "F.Cu" "F.Mask" "F.Paste")
			(net "PWRGD_P3V3_NIC1_D")
		)
	)
	(footprint ""
		(layer "F.Cu")
		(at 136.445244 -95.814642 180)
		(property "Reference" "R1590"
			(at 0 0 180)
			(layer "F.SilkS")
			(hide yes)
			(effects
				(font
					(size 1.27 1.27)
				)
			)
		)
		(property "Value" ""
			(at 0 0 180)
			(layer "F.Fab")
			(effects
				(font
					(size 1.27 1.27)
				)
			)
		)
		(duplicate_pad_numbers_are_jumpers no)
		(fp_line
			(start 0.7874 0.4064)
			(end -0.7874 0.4064)
			(stroke
				(width 0.1524)
				(type default)
			)
			(layer "F.SilkS")
		)
		(fp_line
			(start 0.7874 -0.4064)
			(end 0.7874 0.4064)
			(stroke
				(width 0.1524)
				(type default)
			)
			(layer "F.SilkS")
		)
		(fp_line
			(start -0.7874 0.4064)
			(end -0.7874 -0.4064)
			(stroke
				(width 0.1524)
				(type default)
			)
			(layer "F.SilkS")
		)
		(fp_line
			(start -0.7874 -0.4064)
			(end 0.7874 -0.4064)
			(stroke
				(width 0.1524)
				(type default)
			)
			(layer "F.SilkS")
		)
		(fp_line
			(start 0.67945 0.3048)
			(end 0.120396 0.3048)
			(stroke
				(width 0.1)
				(type default)
			)
			(layer "F.Fab")
		)
		(fp_line
			(start 0.67945 -0.3048)
			(end 0.67945 0.3048)
			(stroke
				(width 0.1)
				(type default)
			)
			(layer "F.Fab")
		)
		(fp_line
			(start 0.12065 -0.2794)
			(end 0.12065 -0.3048)
			(stroke
				(width 0.1)
				(type default)
			)
			(layer "F.Fab")
		)
		(fp_line
			(start 0.12065 -0.3048)
			(end 0.67945 -0.3048)
			(stroke
				(width 0.1)
				(type default)
			)
			(layer "F.Fab")
		)
		(fp_line
			(start 0.120396 0.3048)
			(end 0.120396 0.2794)
			(stroke
				(width 0.1)
				(type default)
			)
			(layer "F.Fab")
		)
		(fp_line
			(start 0.120396 0.2794)
			(end -0.12065 0.2794)
			(stroke
				(width 0.1)
				(type default)
			)
			(layer "F.Fab")
		)
		(fp_line
			(start -0.12065 0.3048)
			(end -0.67945 0.3048)
			(stroke
				(width 0.1)
				(type default)
			)
			(layer "F.Fab")
		)
		(fp_line
			(start -0.12065 0.2794)
			(end -0.12065 0.3048)
			(stroke
				(width 0.1)
				(type default)
			)
			(layer "F.Fab")
		)
		(fp_line
			(start -0.12065 -0.2794)
			(end 0.12065 -0.2794)
			(stroke
				(width 0.1)
				(type default)
			)
			(layer "F.Fab")
		)
		(fp_line
			(start -0.12065 -0.305054)
			(end -0.12065 -0.2794)
			(stroke
				(width 0.1)
				(type default)
			)
			(layer "F.Fab")
		)
		(fp_line
			(start -0.67945 0.3048)
			(end -0.67945 -0.305054)
			(stroke
				(width 0.1)
				(type default)
			)
			(layer "F.Fab")
		)
		(fp_line
			(start -0.67945 -0.305054)
			(end -0.12065 -0.305054)
			(stroke
				(width 0.1)
				(type default)
			)
			(layer "F.Fab")
		)
		(pad "1" smd circle
			(at -0.40005 0 180)
			(size 0 0)
			(layers "F.Cu" "F.Mask" "F.Paste")
			(net "SMB_BIC_I2C9_MUX0_SSD7_R_SCL")
		)
		(pad "2" smd circle
			(at 0.40005 0 180)
			(size 0 0)
			(layers "F.Cu" "F.Mask" "F.Paste")
			(net "SMB_BIC_I2C9_MUX0_SSD7_SCL")
		)
	)
)
